(kicad_pcb
	(version 20241229)
	(generator "pcbnew")
	(generator_version "9.0")
	(general
		(thickness 1.599998)
		(legacy_teardrops no)
	)
	(paper "A4")
	(title_block
		(date "2023-02-12")
		(rev "1.1.5")
		(comment 9 "footprint 164 of 473 (U4), pads 1-73 of 73")
	)
	(layers
		(0 "F.Cu" signal)
		(4 "In1.Cu" power "In1.GND")
		(6 "In2.Cu" signal)
		(8 "In3.Cu" power "In3.GND")
		(10 "In4.Cu" power "In4.VCC")
		(12 "In5.Cu" signal)
		(14 "In6.Cu" power "In6.VCC")
		(2 "B.Cu" signal)
		(9 "F.Adhes" user "F.Adhesive")
		(11 "B.Adhes" user "B.Adhesive")
		(13 "F.Paste" user)
		(15 "B.Paste" user)
		(5 "F.SilkS" user "F.Silkscreen")
		(7 "B.SilkS" user "B.Silkscreen")
		(1 "F.Mask" user)
		(3 "B.Mask" user)
		(17 "Dwgs.User" user "User.Drawings")
		(19 "Cmts.User" user "User.Comments")
		(21 "Eco1.User" user "User.Eco1")
		(23 "Eco2.User" user "User.Eco2")
		(25 "Edge.Cuts" user)
		(27 "Margin" user)
		(31 "F.CrtYd" user "F.Courtyard")
		(29 "B.CrtYd" user "B.Courtyard")
		(35 "F.Fab" user)
		(33 "B.Fab" user)
	)
	(footprint "antmicro-footprints:QFN-56-1EP_8x8mm_P0.5mm"
		(layer "F.Cu")
		(at 140.75 107.849 90)
		(descr "QFN 56 Pin")
		(tags "QFN")
		(property "Reference" "U4"
			(at 0 -5.321 90)
			(layer "F.SilkS")
			(effects
				(font
					(size 0.7 0.7)
					(thickness 0.15)
				)
				(justify left bottom)
			)
		)
		(property "Value" "FT4232H_VQFN"
			(at 0 5.32 90)
			(layer "F.Fab")
			(effects
				(font
					(size 0.7 0.7)
					(thickness 0.15)
				)
				(justify left bottom)
			)
		)
		(property "Description" "Interface Bridges, USB to UART, MPSSE, 1.62 V, 1.98 V, VQFN, 56 Pins, -40 °C"
			(at 0 0 90)
			(layer "F.Fab")
			(hide yes)
			(effects
				(font
					(size 1.27 1.27)
					(thickness 0.15)
				)
			)
		)
		(property "Author" "Antmicro"
			(at 248.599 -32.901 0)
			(layer "F.Fab")
			(hide yes)
			(effects
				(font
					(size 1 1)
					(thickness 0.15)
				)
			)
		)
		(property "License" "Apache-2.0"
			(at 248.599 -32.901 0)
			(layer "F.Fab")
			(hide yes)
			(effects
				(font
					(size 1 1)
					(thickness 0.15)
				)
			)
		)
		(property "MPN" "FT4232H-56Q-REEL"
			(at 248.599 -32.901 0)
			(layer "F.Fab")
			(hide yes)
			(effects
				(font
					(size 1 1)
					(thickness 0.15)
				)
			)
		)
		(property "Manufacturer" "FTDI Chip"
			(at 248.599 -32.901 0)
			(layer "F.Fab")
			(hide yes)
			(effects
				(font
					(size 1 1)
					(thickness 0.15)
				)
			)
		)
		(sheetname "Interfaces")
		(sheetfile "interfaces.kicad_sch")
		(attr smd)
		(pad "" smd roundrect
			(at -2.101 -2.101 90)
			(size 1.13 1.13)
			(layers "F.Paste")
			(roundrect_rratio 0.221239)
		)
		(pad "" smd roundrect
			(at -2.101 -0.7 90)
			(size 1.13 1.13)
			(layers "F.Paste")
			(roundrect_rratio 0.221239)
		)
		(pad "" smd roundrect
			(at -2.101 0.699 90)
			(size 1.13 1.13)
			(layers "F.Paste")
			(roundrect_rratio 0.221239)
		)
		(pad "" smd roundrect
			(at -2.101 2.1 90)
			(size 1.13 1.13)
			(layers "F.Paste")
			(roundrect_rratio 0.221239)
		)
		(pad "" smd roundrect
			(at -0.7 -2.101 90)
			(size 1.13 1.13)
			(layers "F.Paste")
			(roundrect_rratio 0.221239)
		)
		(pad "" smd roundrect
			(at -0.7 -0.7 90)
			(size 1.13 1.13)
			(layers "F.Paste")
			(roundrect_rratio 0.221239)
		)
		(pad "" smd roundrect
			(at -0.7 0.699 90)
			(size 1.13 1.13)
			(layers "F.Paste")
			(roundrect_rratio 0.221239)
		)
		(pad "" smd roundrect
			(at -0.7 2.1 90)
			(size 1.13 1.13)
			(layers "F.Paste")
			(roundrect_rratio 0.221239)
		)
		(pad "" smd roundrect
			(at 0.699 -2.101 90)
			(size 1.13 1.13)
			(layers "F.Paste")
			(roundrect_rratio 0.221239)
		)
		(pad "" smd roundrect
			(at 0.699 -0.7 90)
			(size 1.13 1.13)
			(layers "F.Paste")
			(roundrect_rratio 0.221239)
		)
		(pad "" smd roundrect
			(at 0.699 0.699 90)
			(size 1.13 1.13)
			(layers "F.Paste")
			(roundrect_rratio 0.221239)
		)
		(pad "" smd roundrect
			(at 0.699 2.1 90)
			(size 1.13 1.13)
			(layers "F.Paste")
			(roundrect_rratio 0.221239)
		)
		(pad "" smd roundrect
			(at 2.1 -2.101 90)
			(size 1.13 1.13)
			(layers "F.Paste")
			(roundrect_rratio 0.221239)
		)
		(pad "" smd roundrect
			(at 2.1 -0.7 90)
			(size 1.13 1.13)
			(layers "F.Paste")
			(roundrect_rratio 0.221239)
		)
		(pad "" smd roundrect
			(at 2.1 0.699 90)
			(size 1.13 1.13)
			(layers "F.Paste")
			(roundrect_rratio 0.221239)
		)
		(pad "" smd roundrect
			(at 2.1 2.1 90)
			(size 1.13 1.13)
			(layers "F.Paste")
			(roundrect_rratio 0.221239)
		)
		(pad "1" smd roundrect
			(at -3.938 -3.25 90)
			(size 0.875 0.3)
			(layers "F.Cu" "F.Mask" "F.Paste")
			(roundrect_rratio 0.25)
			(net 549 "unconnected-(U4-EECS-Pad1)")
			(pinfunction "EECS")
			(pintype "bidirectional+no_connect")
		)
		(pad "2" smd roundrect
			(at -3.938 -2.75 90)
			(size 0.875 0.3)
			(layers "F.Cu" "F.Mask" "F.Paste")
			(roundrect_rratio 0.25)
			(net 2 "/Interfaces/1V8_FT")
			(pinfunction "V_{CORE}")
			(pintype "power_in")
		)
		(pad "3" smd roundrect
			(at -3.938 -2.25 90)
			(size 0.875 0.3)
			(layers "F.Cu" "F.Mask" "F.Paste")
			(roundrect_rratio 0.25)
			(net 3 "Net-(U4-OSCI)")
			(pinfunction "OSCI")
			(pintype "input")
		)
		(pad "4" smd roundrect
			(at -3.938 -1.75 90)
			(size 0.875 0.3)
			(layers "F.Cu" "F.Mask" "F.Paste")
			(roundrect_rratio 0.25)
			(net 4 "Net-(U4-OSCO)")
			(pinfunction "OSCO")
			(pintype "output")
		)
		(pad "5" smd roundrect
			(at -3.938 -1.25 90)
			(size 0.875 0.3)
			(layers "F.Cu" "F.Mask" "F.Paste")
			(roundrect_rratio 0.25)
			(net 653 "/Interfaces/VPHY")
			(pinfunction "V_{PHY}")
			(pintype "power_in")
		)
		(pad "6" smd roundrect
			(at -3.938 -0.75 90)
			(size 0.875 0.3)
			(layers "F.Cu" "F.Mask" "F.Paste")
			(roundrect_rratio 0.25)
			(net 239 "Net-(U4-REF)")
			(pinfunction "REF")
			(pintype "input")
		)
		(pad "7" smd roundrect
			(at -3.938 -0.25 90)
			(size 0.875 0.3)
			(layers "F.Cu" "F.Mask" "F.Paste")
			(roundrect_rratio 0.25)
			(net 7 "DBG_USB_N")
			(pinfunction "D-")
			(pintype "bidirectional")
		)
		(pad "8" smd roundrect
			(at -3.938 0.249 90)
			(size 0.875 0.3)
			(layers "F.Cu" "F.Mask" "F.Paste")
			(roundrect_rratio 0.25)
			(net 6 "DBG_USB_P")
			(pinfunction "D+")
			(pintype "bidirectional")
		)
		(pad "9" smd roundrect
			(at -3.938 0.749 90)
			(size 0.875 0.3)
			(layers "F.Cu" "F.Mask" "F.Paste")
			(roundrect_rratio 0.25)
			(net 652 "/Interfaces/VPLL")
			(pinfunction "V_{PLL}")
			(pintype "power_in")
		)
		(pad "10" smd roundrect
			(at -3.938 1.249 90)
			(size 0.875 0.3)
			(layers "F.Cu" "F.Mask" "F.Paste")
			(roundrect_rratio 0.25)
			(net 5 "GND")
			(pinfunction "TEST")
			(pintype "input")
		)
		(pad "11" smd roundrect
			(at -3.938 1.749 90)
			(size 0.875 0.3)
			(layers "F.Cu" "F.Mask" "F.Paste")
			(roundrect_rratio 0.25)
			(net 240 "Net-(U4-~{RESET})")
			(pinfunction "~{RESET}")
			(pintype "input")
		)
		(pad "12" smd roundrect
			(at -3.938 2.249 90)
			(size 0.875 0.3)
			(layers "F.Cu" "F.Mask" "F.Paste")
			(roundrect_rratio 0.25)
			(net 241 "Net-(U4-ADBUS0)")
			(pinfunction "ADBUS0")
			(pintype "bidirectional")
		)
		(pad "13" smd roundrect
			(at -3.938 2.749 90)
			(size 0.875 0.3)
			(layers "F.Cu" "F.Mask" "F.Paste")
			(roundrect_rratio 0.25)
			(net 242 "Net-(U4-ADBUS1)")
			(pinfunction "ADBUS1")
			(pintype "bidirectional")
		)
		(pad "14" smd roundrect
			(at -3.938 3.249 90)
			(size 0.875 0.3)
			(layers "F.Cu" "F.Mask" "F.Paste")
			(roundrect_rratio 0.25)
			(net 243 "Net-(U4-ADBUS2)")
			(pinfunction "ADBUS2")
			(pintype "bidirectional")
		)
		(pad "15" smd roundrect
			(at -3.25 3.937 180)
			(size 0.875 0.3)
			(layers "F.Cu" "F.Mask" "F.Paste")
			(roundrect_rratio 0.25)
			(net 245 "Net-(U4-ADBUS3)")
			(pinfunction "ADBUS3")
			(pintype "bidirectional")
		)
		(pad "16" smd roundrect
			(at -2.75 3.937 180)
			(size 0.875 0.3)
			(layers "F.Cu" "F.Mask" "F.Paste")
			(roundrect_rratio 0.25)
			(net 459 "3V3_SYS")
			(pinfunction "V_{CCIO}")
			(pintype "power_in")
		)
		(pad "17" smd roundrect
			(at -2.25 3.937 180)
			(size 0.875 0.3)
			(layers "F.Cu" "F.Mask" "F.Paste")
			(roundrect_rratio 0.25)
			(net 554 "unconnected-(U4-ADBUS4-Pad17)")
			(pinfunction "ADBUS4")
			(pintype "bidirectional+no_connect")
		)
		(pad "18" smd roundrect
			(at -1.75 3.937 180)
			(size 0.875 0.3)
			(layers "F.Cu" "F.Mask" "F.Paste")
			(roundrect_rratio 0.25)
			(net 265 "Net-(U4-ADBUS5)")
			(pinfunction "ADBUS5")
			(pintype "bidirectional")
		)
		(pad "19" smd roundrect
			(at -1.25 3.937 180)
			(size 0.875 0.3)
			(layers "F.Cu" "F.Mask" "F.Paste")
			(roundrect_rratio 0.25)
			(net 558 "unconnected-(U4-ADBUS6-Pad19)")
			(pinfunction "ADBUS6")
			(pintype "bidirectional+no_connect")
		)
		(pad "20" smd roundrect
			(at -0.75 3.937 180)
			(size 0.875 0.3)
			(layers "F.Cu" "F.Mask" "F.Paste")
			(roundrect_rratio 0.25)
			(net 559 "unconnected-(U4-ADBUS7-Pad20)")
			(pinfunction "ADBUS7")
			(pintype "bidirectional+no_connect")
		)
		(pad "21" smd roundrect
			(at -0.25 3.937 180)
			(size 0.875 0.3)
			(layers "F.Cu" "F.Mask" "F.Paste")
			(roundrect_rratio 0.25)
			(net 5 "GND")
			(pinfunction "GND")
			(pintype "power_in")
		)
		(pad "22" smd roundrect
			(at 0.249 3.937 180)
			(size 0.875 0.3)
			(layers "F.Cu" "F.Mask" "F.Paste")
			(roundrect_rratio 0.25)
			(net 246 "Net-(U4-BDBUS0)")
			(pinfunction "BDBUS0")
			(pintype "bidirectional")
		)
		(pad "23" smd roundrect
			(at 0.749 3.937 180)
			(size 0.875 0.3)
			(layers "F.Cu" "F.Mask" "F.Paste")
			(roundrect_rratio 0.25)
			(net 247 "Net-(U4-BDBUS1)")
			(pinfunction "BDBUS1")
			(pintype "bidirectional")
		)
		(pad "24" smd roundrect
			(at 1.249 3.937 180)
			(size 0.875 0.3)
			(layers "F.Cu" "F.Mask" "F.Paste")
			(roundrect_rratio 0.25)
			(net 248 "Net-(U4-BDBUS2)")
			(pinfunction "BDBUS2")
			(pintype "bidirectional")
		)
		(pad "25" smd roundrect
			(at 1.749 3.937 180)
			(size 0.875 0.3)
			(layers "F.Cu" "F.Mask" "F.Paste")
			(roundrect_rratio 0.25)
			(net 249 "Net-(U4-BDBUS3)")
			(pinfunction "BDBUS3")
			(pintype "bidirectional")
		)
		(pad "26" smd roundrect
			(at 2.249 3.937 180)
			(size 0.875 0.3)
			(layers "F.Cu" "F.Mask" "F.Paste")
			(roundrect_rratio 0.25)
			(net 560 "unconnected-(U4-BDBUS4-Pad26)")
			(pinfunction "BDBUS4")
			(pintype "bidirectional+no_connect")
		)
		(pad "27" smd roundrect
			(at 2.749 3.937 180)
			(size 0.875 0.3)
			(layers "F.Cu" "F.Mask" "F.Paste")
			(roundrect_rratio 0.25)
			(net 250 "Net-(U4-BDBUS5)")
			(pinfunction "BDBUS5")
			(pintype "bidirectional")
		)
		(pad "28" smd roundrect
			(at 3.249 3.937 180)
			(size 0.875 0.3)
			(layers "F.Cu" "F.Mask" "F.Paste")
			(roundrect_rratio 0.25)
			(net 561 "unconnected-(U4-BDBUS6-Pad28)")
			(pinfunction "BDBUS6")
			(pintype "bidirectional+no_connect")
		)
		(pad "29" smd roundrect
			(at 3.937 3.249 90)
			(size 0.875 0.3)
			(layers "F.Cu" "F.Mask" "F.Paste")
			(roundrect_rratio 0.25)
			(net 562 "unconnected-(U4-BDBUS7-Pad29)")
			(pinfunction "BDBUS7")
			(pintype "bidirectional+no_connect")
		)
		(pad "30" smd roundrect
			(at 3.937 2.749 90)
			(size 0.875 0.3)
			(layers "F.Cu" "F.Mask" "F.Paste")
			(roundrect_rratio 0.25)
			(net 563 "unconnected-(U4-~{SUSPEND}-Pad30)")
			(pinfunction "~{SUSPEND}")
			(pintype "output+no_connect")
		)
		(pad "31" smd roundrect
			(at 3.937 2.249 90)
			(size 0.875 0.3)
			(layers "F.Cu" "F.Mask" "F.Paste")
			(roundrect_rratio 0.25)
			(net 2 "/Interfaces/1V8_FT")
			(pinfunction "V_{CORE}")
			(pintype "passive")
		)
		(pad "32" smd roundrect
			(at 3.937 1.749 90)
			(size 0.875 0.3)
			(layers "F.Cu" "F.Mask" "F.Paste")
			(roundrect_rratio 0.25)
			(net 251 "Net-(U4-CDBUS0)")
			(pinfunction "CDBUS0")
			(pintype "bidirectional")
		)
		(pad "33" smd roundrect
			(at 3.937 1.249 90)
			(size 0.875 0.3)
			(layers "F.Cu" "F.Mask" "F.Paste")
			(roundrect_rratio 0.25)
			(net 252 "Net-(U4-CDBUS1)")
			(pinfunction "CDBUS1")
			(pintype "bidirectional")
		)
		(pad "34" smd roundrect
			(at 3.937 0.749 90)
			(size 0.875 0.3)
			(layers "F.Cu" "F.Mask" "F.Paste")
			(roundrect_rratio 0.25)
			(net 564 "unconnected-(U4-CDBUS2-Pad34)")
			(pinfunction "CDBUS2")
			(pintype "bidirectional+no_connect")
		)
		(pad "35" smd roundrect
			(at 3.937 0.249 90)
			(size 0.875 0.3)
			(layers "F.Cu" "F.Mask" "F.Paste")
			(roundrect_rratio 0.25)
			(net 565 "unconnected-(U4-CDBUS3-Pad35)")
			(pinfunction "CDBUS3")
			(pintype "bidirectional+no_connect")
		)
		(pad "36" smd roundrect
			(at 3.937 -0.25 90)
			(size 0.875 0.3)
			(layers "F.Cu" "F.Mask" "F.Paste")
			(roundrect_rratio 0.25)
			(net 459 "3V3_SYS")
			(pinfunction "V_{CCIO}")
			(pintype "passive")
		)
		(pad "37" smd roundrect
			(at 3.937 -0.75 90)
			(size 0.875 0.3)
			(layers "F.Cu" "F.Mask" "F.Paste")
			(roundrect_rratio 0.25)
			(net 566 "unconnected-(U4-CDBUS4-Pad37)")
			(pinfunction "CDBUS4")
			(pintype "bidirectional+no_connect")
		)
		(pad "38" smd roundrect
			(at 3.937 -1.25 90)
			(size 0.875 0.3)
			(layers "F.Cu" "F.Mask" "F.Paste")
			(roundrect_rratio 0.25)
			(net 567 "unconnected-(U4-CDBUS5-Pad38)")
			(pinfunction "CDBUS5")
			(pintype "bidirectional+no_connect")
		)
		(pad "39" smd roundrect
			(at 3.937 -1.75 90)
			(size 0.875 0.3)
			(layers "F.Cu" "F.Mask" "F.Paste")
			(roundrect_rratio 0.25)
			(net 568 "unconnected-(U4-CDBUS6-Pad39)")
			(pinfunction "CDBUS6")
			(pintype "bidirectional+no_connect")
		)
		(pad "40" smd roundrect
			(at 3.937 -2.25 90)
			(size 0.875 0.3)
			(layers "F.Cu" "F.Mask" "F.Paste")
			(roundrect_rratio 0.25)
			(net 569 "unconnected-(U4-CDBUS7-Pad40)")
			(pinfunction "CDBUS7")
			(pintype "bidirectional+no_connect")
		)
		(pad "41" smd roundrect
			(at 3.937 -2.75 90)
			(size 0.875 0.3)
			(layers "F.Cu" "F.Mask" "F.Paste")
			(roundrect_rratio 0.25)
			(net 5 "GND")
			(pinfunction "GND")
			(pintype "passive")
		)
		(pad "42" smd roundrect
			(at 3.937 -3.25 90)
			(size 0.875 0.3)
			(layers "F.Cu" "F.Mask" "F.Paste")
			(roundrect_rratio 0.25)
			(net 253 "Net-(U4-DDBUS0)")
			(pinfunction "DDBUS0")
			(pintype "bidirectional")
		)
		(pad "43" smd roundrect
			(at 3.249 -3.938 180)
			(size 0.875 0.3)
			(layers "F.Cu" "F.Mask" "F.Paste")
			(roundrect_rratio 0.25)
			(net 2 "/Interfaces/1V8_FT")
			(pinfunction "V_{REGOUT}")
			(pintype "power_out")
		)
		(pad "44" smd roundrect
			(at 2.749 -3.938 180)
			(size 0.875 0.3)
			(layers "F.Cu" "F.Mask" "F.Paste")
			(roundrect_rratio 0.25)
			(net 459 "3V3_SYS")
			(pinfunction "V_{REGIN}")
			(pintype "power_in")
		)
		(pad "45" smd roundrect
			(at 2.249 -3.938 180)
			(size 0.875 0.3)
			(layers "F.Cu" "F.Mask" "F.Paste")
			(roundrect_rratio 0.25)
			(net 5 "GND")
			(pinfunction "GND")
			(pintype "passive")
		)
		(pad "46" smd roundrect
			(at 1.749 -3.938 180)
			(size 0.875 0.3)
			(layers "F.Cu" "F.Mask" "F.Paste")
			(roundrect_rratio 0.25)
			(net 254 "Net-(U4-DDBUS1)")
			(pinfunction "DDBUS1")
			(pintype "bidirectional")
		)
		(pad "47" smd roundrect
			(at 1.249 -3.938 180)
			(size 0.875 0.3)
			(layers "F.Cu" "F.Mask" "F.Paste")
			(roundrect_rratio 0.25)
			(net 570 "unconnected-(U4-DDBUS2-Pad47)")
			(pinfunction "DDBUS2")
			(pintype "bidirectional+no_connect")
		)
		(pad "48" smd roundrect
			(at 0.749 -3.938 180)
			(size 0.875 0.3)
			(layers "F.Cu" "F.Mask" "F.Paste")
			(roundrect_rratio 0.25)
			(net 571 "unconnected-(U4-DDBUS3-Pad48)")
			(pinfunction "DDBUS3")
			(pintype "bidirectional+no_connect")
		)
		(pad "49" smd roundrect
			(at 0.249 -3.938 180)
			(size 0.875 0.3)
			(layers "F.Cu" "F.Mask" "F.Paste")
			(roundrect_rratio 0.25)
			(net 572 "unconnected-(U4-DDBUS4-Pad49)")
			(pinfunction "DDBUS4")
			(pintype "bidirectional+no_connect")
		)
		(pad "50" smd roundrect
			(at -0.25 -3.938 180)
			(size 0.875 0.3)
			(layers "F.Cu" "F.Mask" "F.Paste")
			(roundrect_rratio 0.25)
			(net 459 "3V3_SYS")
			(pinfunction "V_{CCIO}")
			(pintype "passive")
		)
		(pad "51" smd roundrect
			(at -0.75 -3.938 180)
			(size 0.875 0.3)
			(layers "F.Cu" "F.Mask" "F.Paste")
			(roundrect_rratio 0.25)
			(net 573 "unconnected-(U4-DDBUS5-Pad51)")
			(pinfunction "DDBUS5")
			(pintype "bidirectional+no_connect")
		)
		(pad "52" smd roundrect
			(at -1.25 -3.938 180)
			(size 0.875 0.3)
			(layers "F.Cu" "F.Mask" "F.Paste")
			(roundrect_rratio 0.25)
			(net 604 "unconnected-(U4-DDBUS6-Pad52)")
			(pinfunction "DDBUS6")
			(pintype "bidirectional+no_connect")
		)
		(pad "53" smd roundrect
			(at -1.75 -3.938 180)
			(size 0.875 0.3)
			(layers "F.Cu" "F.Mask" "F.Paste")
			(roundrect_rratio 0.25)
			(net 606 "unconnected-(U4-DDBUS7-Pad53)")
			(pinfunction "DDBUS7")
			(pintype "bidirectional+no_connect")
		)
		(pad "54" smd roundrect
			(at -2.25 -3.938 180)
			(size 0.875 0.3)
			(layers "F.Cu" "F.Mask" "F.Paste")
			(roundrect_rratio 0.25)
			(net 607 "unconnected-(U4-~{PWR_{EN}}-Pad54)")
			(pinfunction "~{PWR_{EN}}")
			(pintype "output+no_connect")
		)
		(pad "55" smd roundrect
			(at -2.75 -3.938 180)
			(size 0.875 0.3)
			(layers "F.Cu" "F.Mask" "F.Paste")
			(roundrect_rratio 0.25)
			(net 608 "unconnected-(U4-EEDATA-Pad55)")
			(pinfunction "EEDATA")
			(pintype "bidirectional+no_connect")
		)
		(pad "56" smd roundrect
			(at -3.25 -3.938 180)
			(size 0.875 0.3)
			(layers "F.Cu" "F.Mask" "F.Paste")
			(roundrect_rratio 0.25)
			(net 634 "unconnected-(U4-EECLK-Pad56)")
			(pinfunction "EECLK")
			(pintype "output+no_connect")
		)
		(pad "57" smd rect
			(at 0 0 90)
			(size 5.9 5.9)
			(layers "F.Cu" "F.Mask")
			(net 5 "GND")
			(pinfunction "GND")
			(pintype "passive")
		)
	)
)
